(kicad_pcb
	(version 20260206)
	(generator "pcbnew")
	(generator_version "10.0")
	(general
		(thickness 1.6)
		(legacy_teardrops no)
	)
	(paper "A4")
	(title_block
		(title "Bryce Canyon_F.DPB_16315-1-OCP.brd")
		(comment 1 "Bryce Canyon / footprints 449-456 of 2223")
	)
	(layers
		(0 "F.Cu" signal "TOP")
		(4 "In1.Cu" signal "L2GND")
		(6 "In2.Cu" signal "L3")
		(8 "In3.Cu" signal "L4GND")
		(10 "In4.Cu" signal "L5")
		(12 "In5.Cu" signal "L6VCC")
		(14 "In6.Cu" signal "L7VCC")
		(16 "In7.Cu" signal "L8")
		(18 "In8.Cu" signal "L9GND")
		(20 "In9.Cu" signal "L10")
		(22 "In10.Cu" signal "L11GND")
		(2 "B.Cu" signal "BOTTOM")
		(9 "F.Adhes" user "F.Adhesive")
		(11 "B.Adhes" user "B.Adhesive")
		(13 "F.Paste" user "Package Geometry/Pastemask Top")
		(15 "B.Paste" user "Package Geometry/Pastemask Bottom")
		(5 "F.SilkS" user "Ref Des/Silkscreen Top")
		(7 "B.SilkS" user "Ref Des/Silkscreen Bottom")
		(1 "F.Mask" user "Board Geometry/Soldermask Top")
		(3 "B.Mask" user "Board Geometry/Soldermask Bottom")
		(17 "Dwgs.User" user "User.Drawings")
		(19 "Cmts.User" user "User.Comments")
		(21 "Eco1.User" user "User.Eco1")
		(23 "Eco2.User" user "User.Eco2")
		(25 "Edge.Cuts" user "Board Geometry/Outline")
		(27 "Margin" user)
		(31 "F.CrtYd" user "Package Geometry/Place Bound Top")
		(29 "B.CrtYd" user "Package Geometry/Place Bound Bottom")
		(35 "F.Fab" user "Ref Des/Assembly Top")
		(33 "B.Fab" user "Ref Des/Assembly Bottom")
	)
	(footprint ""
		(layer "F.Cu")
		(at 32.508952 -277.750016 -90)
		(property "Reference" "VIA34"
			(at 0 0 270)
			(layer "F.SilkS")
			(hide yes)
			(effects
				(font
					(size 1.27 1.27)
				)
			)
		)
		(property "Value" "100OHM-8L-1D6MM-L18L16-GP"
			(at -3.7211 -4.5085 270)
			(unlocked yes)
			(layer "F.Fab")
			(hide yes)
			(effects
				(font
					(size 1.016 1.016)
					(thickness 0.1524)
				)
			)
		)
		(property "Device Type" "VIA-PCIE-4P-394076"
			(at -3.7211 -6.0325 270)
			(unlocked yes)
			(layer "F.Fab")
			(hide yes)
			(effects
				(font
					(size 1.016 1.016)
					(thickness 0.1524)
				)
			)
		)
		(duplicate_pad_numbers_are_jumpers no)
		(fp_rect
			(start -1.9685 0.381)
			(end 1.9685 -0.381)
			(stroke
				(width 0)
				(type default)
			)
			(fill no)
			(layer "F.CrtYd")
		)
		(fp_rect
			(start -1.9685 0.381)
			(end 1.9685 -0.381)
			(stroke
				(width 0)
				(type default)
			)
			(fill no)
			(layer "F.Fab")
		)
		(pad "1" thru_hole circle
			(at -1.5875 0 270)
			(size 0.508 0.508)
			(drill 0.254)
			(layers "*.Cu" "*.Mask")
			(remove_unused_layers no)
			(net "GND")
			(clearance 0.127)
			(thermal_gap 0.127)
		)
		(pad "2" thru_hole circle
			(at -0.5715 0 270)
			(size 0.508 0.508)
			(drill 0.254)
			(layers "*.Cu" "*.Mask")
			(remove_unused_layers no)
			(net "PHY_DRV_A_TO_SCC_A_0_DP")
			(clearance 0.127)
			(thermal_gap 0.127)
		)
		(pad "3" thru_hole circle
			(at 0.5715 0 270)
			(size 0.508 0.508)
			(drill 0.254)
			(layers "*.Cu" "*.Mask")
			(remove_unused_layers no)
			(net "PHY_DRV_A_TO_SCC_A_0_DN")
			(clearance 0.127)
			(thermal_gap 0.127)
		)
		(pad "4" thru_hole circle
			(at 1.5875 0 270)
			(size 0.508 0.508)
			(drill 0.254)
			(layers "*.Cu" "*.Mask")
			(remove_unused_layers no)
			(net "GND")
			(clearance 0.127)
			(thermal_gap 0.127)
		)
	)
	(footprint ""
		(layer "F.Cu")
		(at 156.92374 -141.014196 -90)
		(property "Reference" "R1064"
			(at 0 0 270)
			(layer "F.SilkS")
			(hide yes)
			(effects
				(font
					(size 1.27 1.27)
				)
			)
		)
		(property "Value" "49K9R2F-L-GP"
			(at 0.064008 -3.993896 270)
			(unlocked yes)
			(layer "F.Fab")
			(hide yes)
			(effects
				(font
					(size 1.016 1.016)
					(thickness 0.1524)
				)
			)
		)
		(property "Device Type" "R402H16"
			(at 0.064008 -5.517896 270)
			(unlocked yes)
			(layer "F.Fab")
			(hide yes)
			(effects
				(font
					(size 1.016 1.016)
					(thickness 0.1524)
				)
			)
		)
		(duplicate_pad_numbers_are_jumpers no)
		(fp_line
			(start -0.508 -0.9398)
			(end -0.508 0.9398)
			(stroke
				(width 0.1524)
				(type default)
			)
			(layer "F.SilkS")
		)
		(fp_line
			(start 0.508 -0.9398)
			(end -0.508 -0.9398)
			(stroke
				(width 0.1524)
				(type default)
			)
			(layer "F.SilkS")
		)
		(fp_rect
			(start -0.508 0.9398)
			(end 0.508 -0.9398)
			(stroke
				(width 0)
				(type default)
			)
			(fill no)
			(layer "F.CrtYd")
		)
		(fp_rect
			(start -0.508 0.9398)
			(end 0.508 -0.9398)
			(stroke
				(width 0)
				(type default)
			)
			(fill no)
			(layer "F.Fab")
		)
		(pad "1" smd custom
			(at 0 -0.4445 270)
			(size 0.1397 0.1397)
			(layers "F.Cu" "F.Mask" "F.Paste")
			(net "P12V_A")
			(options
				(clearance outline)
				(anchor circle)
			)
			(primitives
				(gr_poly
					(pts
						(arc
							(start -0.1778 -0.2794)
							(mid -0.249642 -0.249642)
							(end -0.2794 -0.1778)
						)
						(arc
							(start -0.2794 0.1778)
							(mid -0.249642 0.249642)
							(end -0.1778 0.2794)
						)
						(arc
							(start 0.1778 0.2794)
							(mid 0.249642 0.249642)
							(end 0.2794 0.1778)
						)
						(arc
							(start 0.2794 -0.1778)
							(mid 0.249642 -0.249642)
							(end 0.1778 -0.2794)
						)
					)
					(width 0)
					(fill yes)
				)
			)
		)
		(pad "2" smd custom
			(at 0 0.4445 270)
			(size 0.1397 0.1397)
			(layers "F.Cu" "F.Mask" "F.Paste")
			(net "MB0_CM_UV_R")
			(options
				(clearance outline)
				(anchor circle)
			)
			(primitives
				(gr_poly
					(pts
						(arc
							(start -0.1778 -0.2794)
							(mid -0.249642 -0.249642)
							(end -0.2794 -0.1778)
						)
						(arc
							(start -0.2794 0.1778)
							(mid -0.249642 0.249642)
							(end -0.1778 0.2794)
						)
						(arc
							(start 0.1778 0.2794)
							(mid 0.249642 0.249642)
							(end 0.2794 0.1778)
						)
						(arc
							(start 0.2794 -0.1778)
							(mid 0.249642 -0.249642)
							(end 0.1778 -0.2794)
						)
					)
					(width 0)
					(fill yes)
				)
			)
		)
	)
	(footprint ""
		(layer "F.Cu")
		(at 54.546246 -44.871894 -90)
		(property "Reference" "R716"
			(at 0 0 270)
			(layer "F.SilkS")
			(hide yes)
			(effects
				(font
					(size 1.27 1.27)
				)
			)
		)
		(property "Value" "0R2J-2-GP"
			(at 0.064008 -3.993896 270)
			(unlocked yes)
			(layer "F.Fab")
			(hide yes)
			(effects
				(font
					(size 1.016 1.016)
					(thickness 0.1524)
				)
			)
		)
		(property "Device Type" "R402H16"
			(at 0.064008 -5.517896 270)
			(unlocked yes)
			(layer "F.Fab")
			(hide yes)
			(effects
				(font
					(size 1.016 1.016)
					(thickness 0.1524)
				)
			)
		)
		(duplicate_pad_numbers_are_jumpers no)
		(fp_line
			(start -0.508 -0.9398)
			(end -0.508 0.9398)
			(stroke
				(width 0.1524)
				(type default)
			)
			(layer "F.SilkS")
		)
		(fp_line
			(start 0.508 -0.9398)
			(end -0.508 -0.9398)
			(stroke
				(width 0.1524)
				(type default)
			)
			(layer "F.SilkS")
		)
		(fp_rect
			(start -0.508 0.9398)
			(end 0.508 -0.9398)
			(stroke
				(width 0)
				(type default)
			)
			(fill no)
			(layer "F.CrtYd")
		)
		(fp_rect
			(start -0.508 0.9398)
			(end 0.508 -0.9398)
			(stroke
				(width 0)
				(type default)
			)
			(fill no)
			(layer "F.Fab")
		)
		(pad "1" smd custom
			(at 0 -0.4445 270)
			(size 0.1397 0.1397)
			(layers "F.Cu" "F.Mask" "F.Paste")
			(net "DRIVE_A_25_PWR")
			(options
				(clearance outline)
				(anchor circle)
			)
			(primitives
				(gr_poly
					(pts
						(arc
							(start -0.1778 -0.2794)
							(mid -0.249642 -0.249642)
							(end -0.2794 -0.1778)
						)
						(arc
							(start -0.2794 0.1778)
							(mid -0.249642 0.249642)
							(end -0.1778 0.2794)
						)
						(arc
							(start 0.1778 0.2794)
							(mid 0.249642 0.249642)
							(end 0.2794 0.1778)
						)
						(arc
							(start 0.2794 -0.1778)
							(mid 0.249642 -0.249642)
							(end 0.1778 -0.2794)
						)
					)
					(width 0)
					(fill yes)
				)
			)
		)
		(pad "2" smd custom
			(at 0 0.4445 270)
			(size 0.1397 0.1397)
			(layers "F.Cu" "F.Mask" "F.Paste")
			(net "SW_PWR_R_HDD25")
			(options
				(clearance outline)
				(anchor circle)
			)
			(primitives
				(gr_poly
					(pts
						(arc
							(start -0.1778 -0.2794)
							(mid -0.249642 -0.249642)
							(end -0.2794 -0.1778)
						)
						(arc
							(start -0.2794 0.1778)
							(mid -0.249642 0.249642)
							(end -0.1778 0.2794)
						)
						(arc
							(start 0.1778 0.2794)
							(mid 0.249642 0.249642)
							(end 0.2794 0.1778)
						)
						(arc
							(start 0.2794 -0.1778)
							(mid 0.249642 -0.249642)
							(end 0.1778 -0.2794)
						)
					)
					(width 0)
					(fill yes)
				)
			)
		)
	)
	(footprint ""
		(layer "F.Cu")
		(at 361.4928 -145.1864 -90)
		(property "Reference" "Q221"
			(at 0 0 270)
			(layer "F.SilkS")
			(hide yes)
			(effects
				(font
					(size 1.27 1.27)
				)
			)
		)
		(property "Value" "MMBT3904-3-GP"
			(at 0.10287 -10.29843 270)
			(unlocked yes)
			(layer "F.Fab")
			(hide yes)
			(effects
				(font
					(size 1.016 1.016)
					(thickness 0.1524)
				)
			)
		)
		(property "Device Type" "SOT23CBE2D4H44"
			(at 0.10287 -12.20343 270)
			(unlocked yes)
			(layer "F.Fab")
			(hide yes)
			(effects
				(font
					(size 1.016 1.016)
					(thickness 0.1524)
				)
			)
		)
		(duplicate_pad_numbers_are_jumpers no)
		(fp_line
			(start -1.651 1.778)
			(end 1.651 1.778)
			(stroke
				(width 0.1524)
				(type default)
			)
			(layer "F.SilkS")
		)
		(fp_line
			(start 1.651 1.778)
			(end 1.651 -1.778)
			(stroke
				(width 0.1524)
				(type default)
			)
			(layer "F.SilkS")
		)
		(fp_line
			(start -1.651 -1.778)
			(end -1.651 1.778)
			(stroke
				(width 0.1524)
				(type default)
			)
			(layer "F.SilkS")
		)
		(fp_line
			(start 1.651 -1.778)
			(end -1.651 -1.778)
			(stroke
				(width 0.1524)
				(type default)
			)
			(layer "F.SilkS")
		)
		(fp_poly
			(pts
				(xy -1.778 1.8796) (xy -1.778 -1.8796) (xy 1.778 -1.8796) (xy 1.778 1.8796)
			)
			(stroke
				(width 0)
				(type default)
			)
			(fill no)
			(layer "F.CrtYd")
		)
		(fp_poly
			(pts
				(xy -1.778 1.8796) (xy -1.778 -1.8796) (xy 1.778 -1.8796) (xy 1.778 1.8796)
			)
			(stroke
				(width 0)
				(type default)
			)
			(fill no)
			(layer "F.Fab")
		)
		(pad "B" smd custom
			(at -0.98425 0.9525 270)
			(size 0.1905 0.1905)
			(layers "F.Cu" "F.Mask" "F.Paste")
			(net "MB1_TEMP_B")
			(options
				(clearance outline)
				(anchor circle)
			)
			(primitives
				(gr_poly
					(pts
						(arc
							(start -0.1778 0.5715)
							(mid -0.321484 0.511984)
							(end -0.381 0.3683)
						)
						(arc
							(start -0.381 -0.3683)
							(mid -0.321484 -0.511984)
							(end -0.1778 -0.5715)
						)
						(arc
							(start 0.1778 -0.5715)
							(mid 0.321484 -0.511984)
							(end 0.381 -0.3683)
						)
						(arc
							(start 0.381 0.3683)
							(mid 0.321484 0.511984)
							(end 0.1778 0.5715)
						)
					)
					(width 0)
					(fill yes)
				)
			)
		)
		(pad "C" smd custom
			(at 0 -0.9525 270)
			(size 0.1905 0.1905)
			(layers "F.Cu" "F.Mask" "F.Paste")
			(net "MB1_TEMP_B")
			(options
				(clearance outline)
				(anchor circle)
			)
			(primitives
				(gr_poly
					(pts
						(arc
							(start -0.1778 0.5715)
							(mid -0.321484 0.511984)
							(end -0.381 0.3683)
						)
						(arc
							(start -0.381 -0.3683)
							(mid -0.321484 -0.511984)
							(end -0.1778 -0.5715)
						)
						(arc
							(start 0.1778 -0.5715)
							(mid 0.321484 -0.511984)
							(end 0.381 -0.3683)
						)
						(arc
							(start 0.381 0.3683)
							(mid 0.321484 0.511984)
							(end 0.1778 0.5715)
						)
					)
					(width 0)
					(fill yes)
				)
			)
		)
		(pad "E" smd custom
			(at 0.98425 0.9525 270)
			(size 0.1905 0.1905)
			(layers "F.Cu" "F.Mask" "F.Paste")
			(net "MB1_TEMP_E")
			(options
				(clearance outline)
				(anchor circle)
			)
			(primitives
				(gr_poly
					(pts
						(arc
							(start -0.1778 0.5715)
							(mid -0.321484 0.511984)
							(end -0.381 0.3683)
						)
						(arc
							(start -0.381 -0.3683)
							(mid -0.321484 -0.511984)
							(end -0.1778 -0.5715)
						)
						(arc
							(start 0.1778 -0.5715)
							(mid 0.321484 -0.511984)
							(end 0.381 -0.3683)
						)
						(arc
							(start 0.381 0.3683)
							(mid 0.321484 0.511984)
							(end 0.1778 0.5715)
						)
					)
					(width 0)
					(fill yes)
				)
			)
		)
	)
	(footprint ""
		(layer "F.Cu")
		(at 267.174726 -136.672066 -90)
		(property "Reference" "TP198"
			(at 0 0 270)
			(layer "F.SilkS")
			(hide yes)
			(effects
				(font
					(size 1.27 1.27)
				)
			)
		)
		(property "Value" "TPAD32-GP"
			(at -0.0508 -1.6764 270)
			(unlocked yes)
			(layer "F.Fab")
			(hide yes)
			(effects
				(font
					(size 1.016 1.016)
					(thickness 0.1524)
				)
			)
		)
		(property "Device Type" "TPAD32"
			(at -0.0508 -3.2004 270)
			(unlocked yes)
			(layer "F.Fab")
			(hide yes)
			(effects
				(font
					(size 1.016 1.016)
					(thickness 0.1524)
				)
			)
		)
		(duplicate_pad_numbers_are_jumpers no)
		(fp_poly
			(pts
				(arc
					(start 0 -0.4064)
					(mid 0 0.4064)
					(end 0 -0.4064)
				)
			)
			(stroke
				(width 0)
				(type default)
			)
			(fill no)
			(layer "F.CrtYd")
		)
		(fp_poly
			(pts
				(arc
					(start 0 -0.7112)
					(mid 0 0.7112)
					(end 0 -0.7112)
				)
			)
			(stroke
				(width 0)
				(type default)
			)
			(fill no)
			(layer "F.Fab")
		)
		(pad "1" smd circle
			(at 0 0 270)
			(size 0.8128 0.8128)
			(layers "F.Cu" "F.Mask" "F.Paste")
			(net "TP_PCIE_COMP_B_CLK_1_DP")
		)
	)
	(footprint ""
		(layer "F.Cu")
		(at 67.093846 -183.747918)
		(property "Reference" "TP67"
			(at 0 0 0)
			(layer "F.SilkS")
			(hide yes)
			(effects
				(font
					(size 1.27 1.27)
				)
			)
		)
		(property "Value" "TPAD32-GP"
			(at -0.0508 -1.6764 0)
			(unlocked yes)
			(layer "F.Fab")
			(hide yes)
			(effects
				(font
					(size 1.016 1.016)
					(thickness 0.1524)
				)
			)
		)
		(property "Device Type" "TPAD32"
			(at -0.0508 -3.2004 0)
			(unlocked yes)
			(layer "F.Fab")
			(hide yes)
			(effects
				(font
					(size 1.016 1.016)
					(thickness 0.1524)
				)
			)
		)
		(duplicate_pad_numbers_are_jumpers no)
		(fp_poly
			(pts
				(arc
					(start 0.4064 0)
					(mid -0.4064 0)
					(end 0.4064 0)
				)
			)
			(stroke
				(width 0)
				(type default)
			)
			(fill no)
			(layer "F.CrtYd")
		)
		(fp_poly
			(pts
				(arc
					(start 0.7112 0)
					(mid -0.7112 0)
					(end 0.7112 0)
				)
			)
			(stroke
				(width 0)
				(type default)
			)
			(fill no)
			(layer "F.Fab")
		)
		(pad "1" smd circle
			(at 0 0)
			(size 0.8128 0.8128)
			(layers "F.Cu" "F.Mask" "F.Paste")
			(net "ACT_HDD_13")
		)
	)
	(footprint ""
		(layer "F.Cu")
		(at 127.15875 -277.750016 -90)
		(property "Reference" "VIA40"
			(at 0 0 270)
			(layer "F.SilkS")
			(hide yes)
			(effects
				(font
					(size 1.27 1.27)
				)
			)
		)
		(property "Value" "100OHM-8L-1D6MM-L18L16-GP"
			(at -3.7211 -4.5085 270)
			(unlocked yes)
			(layer "F.Fab")
			(hide yes)
			(effects
				(font
					(size 1.016 1.016)
					(thickness 0.1524)
				)
			)
		)
		(property "Device Type" "VIA-PCIE-4P-394076"
			(at -3.7211 -6.0325 270)
			(unlocked yes)
			(layer "F.Fab")
			(hide yes)
			(effects
				(font
					(size 1.016 1.016)
					(thickness 0.1524)
				)
			)
		)
		(duplicate_pad_numbers_are_jumpers no)
		(fp_rect
			(start -1.9685 0.381)
			(end 1.9685 -0.381)
			(stroke
				(width 0)
				(type default)
			)
			(fill no)
			(layer "F.CrtYd")
		)
		(fp_rect
			(start -1.9685 0.381)
			(end 1.9685 -0.381)
			(stroke
				(width 0)
				(type default)
			)
			(fill no)
			(layer "F.Fab")
		)
		(pad "1" thru_hole circle
			(at -1.5875 0 270)
			(size 0.508 0.508)
			(drill 0.254)
			(layers "*.Cu" "*.Mask")
			(remove_unused_layers no)
			(net "GND")
			(clearance 0.127)
			(thermal_gap 0.127)
		)
		(pad "2" thru_hole circle
			(at -0.5715 0 270)
			(size 0.508 0.508)
			(drill 0.254)
			(layers "*.Cu" "*.Mask")
			(remove_unused_layers no)
			(net "PHY_DRV_A_TO_SCC_A_3_DP")
			(clearance 0.127)
			(thermal_gap 0.127)
		)
		(pad "3" thru_hole circle
			(at 0.5715 0 270)
			(size 0.508 0.508)
			(drill 0.254)
			(layers "*.Cu" "*.Mask")
			(remove_unused_layers no)
			(net "PHY_DRV_A_TO_SCC_A_3_DN")
			(clearance 0.127)
			(thermal_gap 0.127)
		)
		(pad "4" thru_hole circle
			(at 1.5875 0 270)
			(size 0.508 0.508)
			(drill 0.254)
			(layers "*.Cu" "*.Mask")
			(remove_unused_layers no)
			(net "GND")
			(clearance 0.127)
			(thermal_gap 0.127)
		)
	)
	(footprint ""
		(layer "F.Cu")
		(at 341.300054 -269.999968)
		(property "Reference" ""
			(at 0 0 0)
			(layer "F.SilkS")
			(hide yes)
			(effects
				(font
					(size 1.27 1.27)
				)
			)
		)
		(property "Value" "*"
			(at -6.3373 -0.4572 0)
			(unlocked yes)
			(layer "F.Fab")
			(hide yes)
			(effects
				(font
					(size 1.016 1.016)
					(thickness 0.1524)
				)
			)
		)
		(duplicate_pad_numbers_are_jumpers no)
		(fp_poly
			(pts
				(arc
					(start 5.0673 0)
					(mid -5.0673 0)
					(end 5.0673 0)
				)
			)
			(stroke
				(width 0)
				(type default)
			)
			(fill no)
			(layer "B.CrtYd")
		)
		(fp_poly
			(pts
				(arc
					(start 5.0673 0)
					(mid -5.0673 0)
					(end 5.0673 0)
				)
			)
			(stroke
				(width 0)
				(type default)
			)
			(fill no)
			(layer "F.CrtYd")
		)
		(fp_poly
			(pts
				(arc
					(start 5.0673 0)
					(mid -5.0673 0)
					(end 5.0673 0)
				)
			)
			(stroke
				(width 0)
				(type default)
			)
			(fill no)
			(layer "B.Fab")
		)
		(fp_poly
			(pts
				(arc
					(start 5.0673 0)
					(mid -5.0673 0)
					(end 5.0673 0)
				)
			)
			(stroke
				(width 0)
				(type default)
			)
			(fill no)
			(layer "F.Fab")
		)
		(pad "1" thru_hole circle
			(at 0 0)
			(size 9.525 9.525)
			(drill 3.556)
			(layers "*.Cu" "*.Mask")
			(remove_unused_layers no)
			(net "Net_93")
			(clearance -2.4765)
			(thermal_gap 0.3048)
			(padstack
				(mode front_inner_back)
				(layer "Inner"
					(shape circle)
					(size 3.9624 3.9624)
					(clearance 0.3048)
				)
				(layer "B.Cu"
					(shape circle)
					(size 9.525 9.525)
					(clearance -2.4765)
				)
			)
		)
		(zone
			(layers "F.Cu" "B.Cu" "In1.Cu" "In2.Cu" "In3.Cu" "In4.Cu" "In5.Cu" "In6.Cu"
				"In7.Cu" "In8.Cu" "In9.Cu" "In10.Cu"
			)
			(hatch none 0.5)
			(connect_pads
				(clearance 0)
			)
			(min_thickness 0.25)
			(keepout
				(tracks not_allowed)
				(vias allowed)
				(pads allowed)
				(copperpour not_allowed)
				(footprints allowed)
			)
			(placement
				(enabled no)
				(sheetname "")
			)
			(fill
				(thermal_gap 0.5)
				(thermal_bridge_width 0.5)
				(island_removal_mode 0)
			)
			(polygon
				(pts
					(arc
						(start 346.062554 -269.999968)
						(mid 336.537554 -269.999968)
						(end 346.062554 -269.999968)
					)
				)
			)
		)
	)
)
